# T6G (Grand Teton) — schematic netlist excerpt (pin names and nets, part order shuffled) for the footprints in the layout excerpt that follows; sources: Cadence DE-HDL packaged netlist, KiCad conversion of 04192023_DAF0TMB3IC0_F0TG_MB_C_brd_V02_OCP.brd

R3306  Q_RES  0 5% CHIP  pkg 0402LF  page 143 : A = OCP_V3_2_PRSNT_ALL_R_N ; B = OCP_V3_2_PRSNT_ALL_R3_N
C9102  Q_CAP_DIFFBUS  DIFF BUS_0.22UF 6.3V 20% X6S  pkg C0201  page 67 : \1\ = P3E_CPU1_P4_TX_C_DP<1> ; \2\ = P3E_CPU1_P4_TX_DP<1>
R6707  Q_RES  1K 1% CHIP  pkg 0201LF  page 185 : A = P1V8_CPU1_RT_1D ; B = SMB_RT_CPU1_P0_ROM_R_SDA

(kicad_pcb
	(version 20260206)
	(generator "pcbnew")
	(generator_version "10.0")
	(general
		(thickness 1.6)
		(legacy_teardrops no)
	)
	(paper "A4")
	(title_block
		(title "04192023_DAF0TMB3IC0_F0TG_MB_C_brd_V02_OCP.brd")
		(comment 1 "Grand Teton / footprints 4253-4255 of 8354")
	)
	(layers
		(0 "F.Cu" signal "TOP")
		(4 "In1.Cu" signal "GND")
		(6 "In2.Cu" signal "IN1")
		(8 "In3.Cu" signal "GND1")
		(10 "In4.Cu" signal "IN2")
		(12 "In5.Cu" signal "GND2")
		(14 "In6.Cu" signal "IN3")
		(16 "In7.Cu" signal "GND3")
		(18 "In8.Cu" signal "VCC")
		(20 "In9.Cu" signal "VCC1")
		(22 "In10.Cu" signal "GND4")
		(24 "In11.Cu" signal "IN4")
		(26 "In12.Cu" signal "GND5")
		(28 "In13.Cu" signal "IN5")
		(30 "In14.Cu" signal "GND6")
		(32 "In15.Cu" signal "IN6")
		(34 "In16.Cu" signal "GND7")
		(2 "B.Cu" signal "BOTTOM")
		(9 "F.Adhes" user "F.Adhesive")
		(11 "B.Adhes" user "B.Adhesive")
		(13 "F.Paste" user "Package Geometry/Pastemask Top")
		(15 "B.Paste" user "Package Geometry/Pastemask Bottom")
		(5 "F.SilkS" user "Ref Des/Silkscreen Top")
		(7 "B.SilkS" user "Ref Des/Silkscreen Bottom")
		(1 "F.Mask" user "Board Geometry/Soldermask Top")
		(3 "B.Mask" user "Board Geometry/Soldermask Bottom")
		(17 "Dwgs.User" user "User.Drawings")
		(19 "Cmts.User" user "User.Comments")
		(21 "Eco1.User" user "User.Eco1")
		(23 "Eco2.User" user "User.Eco2")
		(25 "Edge.Cuts" user "Board Geometry/Outline")
		(27 "Margin" user)
		(31 "F.CrtYd" user "Package Geometry/Place Bound Top")
		(29 "B.CrtYd" user "Package Geometry/Place Bound Bottom")
		(35 "F.Fab" user "Ref Des/Assembly Top")
		(33 "B.Fab" user "Ref Des/Assembly Bottom")
	)
	(footprint ""
		(layer "F.Cu")
		(at 148.73859 -95.517208 90)
		(property "Reference" "R3306"
			(at 0 0 90)
			(layer "F.SilkS")
			(hide yes)
			(effects
				(font
					(size 1.27 1.27)
				)
			)
		)
		(property "Value" ""
			(at 0 0 90)
			(layer "F.Fab")
			(effects
				(font
					(size 1.27 1.27)
				)
			)
		)
		(duplicate_pad_numbers_are_jumpers no)
		(fp_line
			(start 0.7874 -0.4064)
			(end 0.7874 0.4064)
			(stroke
				(width 0.1524)
				(type default)
			)
			(layer "F.SilkS")
		)
		(fp_line
			(start -0.7874 -0.4064)
			(end 0.7874 -0.4064)
			(stroke
				(width 0.1524)
				(type default)
			)
			(layer "F.SilkS")
		)
		(fp_line
			(start 0.7874 0.4064)
			(end -0.7874 0.4064)
			(stroke
				(width 0.1524)
				(type default)
			)
			(layer "F.SilkS")
		)
		(fp_line
			(start -0.7874 0.4064)
			(end -0.7874 -0.4064)
			(stroke
				(width 0.1524)
				(type default)
			)
			(layer "F.SilkS")
		)
		(fp_line
			(start -0.12065 -0.305054)
			(end -0.12065 -0.2794)
			(stroke
				(width 0.1)
				(type default)
			)
			(layer "F.Fab")
		)
		(fp_line
			(start -0.67945 -0.305054)
			(end -0.12065 -0.305054)
			(stroke
				(width 0.1)
				(type default)
			)
			(layer "F.Fab")
		)
		(fp_line
			(start 0.67945 -0.3048)
			(end 0.67945 0.3048)
			(stroke
				(width 0.1)
				(type default)
			)
			(layer "F.Fab")
		)
		(fp_line
			(start 0.12065 -0.3048)
			(end 0.67945 -0.3048)
			(stroke
				(width 0.1)
				(type default)
			)
			(layer "F.Fab")
		)
		(fp_line
			(start 0.12065 -0.2794)
			(end 0.12065 -0.3048)
			(stroke
				(width 0.1)
				(type default)
			)
			(layer "F.Fab")
		)
		(fp_line
			(start -0.12065 -0.2794)
			(end 0.12065 -0.2794)
			(stroke
				(width 0.1)
				(type default)
			)
			(layer "F.Fab")
		)
		(fp_line
			(start 0.120396 0.2794)
			(end -0.12065 0.2794)
			(stroke
				(width 0.1)
				(type default)
			)
			(layer "F.Fab")
		)
		(fp_line
			(start -0.12065 0.2794)
			(end -0.12065 0.3048)
			(stroke
				(width 0.1)
				(type default)
			)
			(layer "F.Fab")
		)
		(fp_line
			(start 0.67945 0.3048)
			(end 0.120396 0.3048)
			(stroke
				(width 0.1)
				(type default)
			)
			(layer "F.Fab")
		)
		(fp_line
			(start 0.120396 0.3048)
			(end 0.120396 0.2794)
			(stroke
				(width 0.1)
				(type default)
			)
			(layer "F.Fab")
		)
		(fp_line
			(start -0.12065 0.3048)
			(end -0.67945 0.3048)
			(stroke
				(width 0.1)
				(type default)
			)
			(layer "F.Fab")
		)
		(fp_line
			(start -0.67945 0.3048)
			(end -0.67945 -0.305054)
			(stroke
				(width 0.1)
				(type default)
			)
			(layer "F.Fab")
		)
		(pad "1" smd circle
			(at -0.40005 0 90)
			(size 0 0)
			(layers "F.Cu" "F.Mask" "F.Paste")
			(net "OCP_V3_2_PRSNT_ALL_R_N")
		)
		(pad "2" smd circle
			(at 0.40005 0 90)
			(size 0 0)
			(layers "F.Cu" "F.Mask" "F.Paste")
			(net "OCP_V3_2_PRSNT_ALL_R3_N")
		)
	)
	(footprint ""
		(layer "F.Cu")
		(at 180.528468 -47.139098)
		(property "Reference" "C9102"
			(at 0 0 0)
			(layer "F.SilkS")
			(hide yes)
			(effects
				(font
					(size 1.27 1.27)
				)
			)
		)
		(property "Value" ""
			(at 0 0 0)
			(layer "F.Fab")
			(effects
				(font
					(size 1.27 1.27)
				)
			)
		)
		(duplicate_pad_numbers_are_jumpers no)
		(fp_line
			(start -0.299974 -0.150114)
			(end 0.299974 -0.150114)
			(stroke
				(width 0.1)
				(type default)
			)
			(layer "F.Fab")
		)
		(fp_line
			(start -0.299974 0.150114)
			(end -0.299974 -0.150114)
			(stroke
				(width 0.1)
				(type default)
			)
			(layer "F.Fab")
		)
		(fp_line
			(start 0.299974 -0.150114)
			(end 0.299974 0.150114)
			(stroke
				(width 0.1)
				(type default)
			)
			(layer "F.Fab")
		)
		(fp_line
			(start 0.299974 0.150114)
			(end -0.299974 0.150114)
			(stroke
				(width 0.1)
				(type default)
			)
			(layer "F.Fab")
		)
		(pad "1" smd rect
			(at -0.2667 0)
			(size 0.3048 0.381)
			(layers "F.Cu" "F.Mask" "F.Paste")
			(net "P3E_CPU1_P4_TX_C_DP<1>")
		)
		(pad "2" smd rect
			(at 0.2667 0)
			(size 0.3048 0.381)
			(layers "F.Cu" "F.Mask" "F.Paste")
			(net "P3E_CPU1_P4_TX_DP<1>")
		)
	)
	(footprint ""
		(layer "F.Cu")
		(at 102.357682 -394.697966 90)
		(property "Reference" "R6707"
			(at 0 0 90)
			(layer "F.SilkS")
			(hide yes)
			(effects
				(font
					(size 1.27 1.27)
				)
			)
		)
		(property "Value" ""
			(at 0 0 90)
			(layer "F.Fab")
			(effects
				(font
					(size 1.27 1.27)
				)
			)
		)
		(duplicate_pad_numbers_are_jumpers no)
		(fp_line
			(start 0.32512 -0.175006)
			(end 0.32512 0.175006)
			(stroke
				(width 0.1)
				(type default)
			)
			(layer "F.Fab")
		)
		(fp_line
			(start -0.32512 -0.175006)
			(end 0.32512 -0.175006)
			(stroke
				(width 0.1)
				(type default)
			)
			(layer "F.Fab")
		)
		(fp_line
			(start 0.32512 0.175006)
			(end -0.32512 0.175006)
			(stroke
				(width 0.1)
				(type default)
			)
			(layer "F.Fab")
		)
		(fp_line
			(start -0.32512 0.175006)
			(end -0.32512 -0.175006)
			(stroke
				(width 0.1)
				(type default)
			)
			(layer "F.Fab")
		)
		(pad "1" smd rect
			(at -0.2667 0 90)
			(size 0.3048 0.381)
			(layers "F.Cu" "F.Mask" "F.Paste")
			(net "P1V8_CPU1_RT_1D")
		)
		(pad "2" smd rect
			(at 0.2667 0 270)
			(size 0.3048 0.381)
			(layers "F.Cu" "F.Mask" "F.Paste")
			(net "SMB_RT_CPU1_P0_ROM_R_SDA")
		)
	)
)
